(kicad_pcb
	(version 20260206)
	(generator "pcbnew")
	(generator_version "10.0")
	(general
		(thickness 1.6)
		(legacy_teardrops no)
	)
	(paper "A4")
	(title_block
		(title "01162023_DA0F0TEBIF0_F0T_Expander_BD_F_brd_V02_OCP.brd")
		(comment 1 "Grand Teton / footprints 1168-1173 of 9728")
	)
	(layers
		(0 "F.Cu" signal "TOP")
		(4 "In1.Cu" signal "GND")
		(6 "In2.Cu" signal "VCC")
		(8 "In3.Cu" signal "VCC1")
		(10 "In4.Cu" signal "GND1")
		(12 "In5.Cu" signal "IN1")
		(14 "In6.Cu" signal "GND2")
		(16 "In7.Cu" signal "IN2")
		(18 "In8.Cu" signal "GND3")
		(20 "In9.Cu" signal "IN3")
		(22 "In10.Cu" signal "GND4")
		(24 "In11.Cu" signal "IN4")
		(26 "In12.Cu" signal "GND5")
		(28 "In13.Cu" signal "IN5")
		(30 "In14.Cu" signal "GND6")
		(32 "In15.Cu" signal "IN6")
		(34 "In16.Cu" signal "GND7")
		(2 "B.Cu" signal "BOTTOM")
		(9 "F.Adhes" user "F.Adhesive")
		(11 "B.Adhes" user "B.Adhesive")
		(13 "F.Paste" user "Package Geometry/Pastemask Top")
		(15 "B.Paste" user "Package Geometry/Pastemask Bottom")
		(5 "F.SilkS" user "Ref Des/Silkscreen Top")
		(7 "B.SilkS" user "Ref Des/Silkscreen Bottom")
		(1 "F.Mask" user "Board Geometry/Soldermask Top")
		(3 "B.Mask" user "Board Geometry/Soldermask Bottom")
		(17 "Dwgs.User" user "User.Drawings")
		(19 "Cmts.User" user "User.Comments")
		(21 "Eco1.User" user "User.Eco1")
		(23 "Eco2.User" user "User.Eco2")
		(25 "Edge.Cuts" user "Board Geometry/Outline")
		(27 "Margin" user)
		(31 "F.CrtYd" user "Package Geometry/Place Bound Top")
		(29 "B.CrtYd" user "Package Geometry/Place Bound Bottom")
		(35 "F.Fab" user "Ref Des/Assembly Top")
		(33 "B.Fab" user "Ref Des/Assembly Bottom")
	)
	(footprint ""
		(layer "F.Cu")
		(at 308.681882 -38.041072 180)
		(property "Reference" "R6097"
			(at 0 0 180)
			(layer "F.SilkS")
			(hide yes)
			(effects
				(font
					(size 1.27 1.27)
				)
			)
		)
		(property "Value" ""
			(at 0 0 180)
			(layer "F.Fab")
			(effects
				(font
					(size 1.27 1.27)
				)
			)
		)
		(duplicate_pad_numbers_are_jumpers no)
		(fp_line
			(start 0.7874 0.4064)
			(end -0.7874 0.4064)
			(stroke
				(width 0.1524)
				(type default)
			)
			(layer "F.SilkS")
		)
		(fp_line
			(start 0.7874 -0.4064)
			(end 0.7874 0.4064)
			(stroke
				(width 0.1524)
				(type default)
			)
			(layer "F.SilkS")
		)
		(fp_line
			(start -0.7874 0.4064)
			(end -0.7874 -0.4064)
			(stroke
				(width 0.1524)
				(type default)
			)
			(layer "F.SilkS")
		)
		(fp_line
			(start -0.7874 -0.4064)
			(end 0.7874 -0.4064)
			(stroke
				(width 0.1524)
				(type default)
			)
			(layer "F.SilkS")
		)
		(fp_line
			(start 0.67945 0.3048)
			(end 0.120396 0.3048)
			(stroke
				(width 0.1)
				(type default)
			)
			(layer "F.Fab")
		)
		(fp_line
			(start 0.67945 -0.3048)
			(end 0.67945 0.3048)
			(stroke
				(width 0.1)
				(type default)
			)
			(layer "F.Fab")
		)
		(fp_line
			(start 0.12065 -0.2794)
			(end 0.12065 -0.3048)
			(stroke
				(width 0.1)
				(type default)
			)
			(layer "F.Fab")
		)
		(fp_line
			(start 0.12065 -0.3048)
			(end 0.67945 -0.3048)
			(stroke
				(width 0.1)
				(type default)
			)
			(layer "F.Fab")
		)
		(fp_line
			(start 0.120396 0.3048)
			(end 0.120396 0.2794)
			(stroke
				(width 0.1)
				(type default)
			)
			(layer "F.Fab")
		)
		(fp_line
			(start 0.120396 0.2794)
			(end -0.12065 0.2794)
			(stroke
				(width 0.1)
				(type default)
			)
			(layer "F.Fab")
		)
		(fp_line
			(start -0.12065 0.3048)
			(end -0.67945 0.3048)
			(stroke
				(width 0.1)
				(type default)
			)
			(layer "F.Fab")
		)
		(fp_line
			(start -0.12065 0.2794)
			(end -0.12065 0.3048)
			(stroke
				(width 0.1)
				(type default)
			)
			(layer "F.Fab")
		)
		(fp_line
			(start -0.12065 -0.2794)
			(end 0.12065 -0.2794)
			(stroke
				(width 0.1)
				(type default)
			)
			(layer "F.Fab")
		)
		(fp_line
			(start -0.12065 -0.305054)
			(end -0.12065 -0.2794)
			(stroke
				(width 0.1)
				(type default)
			)
			(layer "F.Fab")
		)
		(fp_line
			(start -0.67945 0.3048)
			(end -0.67945 -0.305054)
			(stroke
				(width 0.1)
				(type default)
			)
			(layer "F.Fab")
		)
		(fp_line
			(start -0.67945 -0.305054)
			(end -0.12065 -0.305054)
			(stroke
				(width 0.1)
				(type default)
			)
			(layer "F.Fab")
		)
		(pad "1" smd circle
			(at -0.40005 0 180)
			(size 0 0)
			(layers "F.Cu" "F.Mask" "F.Paste")
			(net "P5V_AUX")
		)
		(pad "2" smd circle
			(at 0.40005 0 180)
			(size 0 0)
			(layers "F.Cu" "F.Mask" "F.Paste")
			(net "P3V3_SSD11_PG_G2")
		)
	)
	(footprint ""
		(layer "F.Cu")
		(at 336.042 -180.975)
		(property "Reference" "R4730"
			(at 0 0 0)
			(layer "F.SilkS")
			(hide yes)
			(effects
				(font
					(size 1.27 1.27)
				)
			)
		)
		(property "Value" ""
			(at 0 0 0)
			(layer "F.Fab")
			(effects
				(font
					(size 1.27 1.27)
				)
			)
		)
		(duplicate_pad_numbers_are_jumpers no)
		(fp_line
			(start -0.7874 -0.4064)
			(end 0.7874 -0.4064)
			(stroke
				(width 0.1524)
				(type default)
			)
			(layer "F.SilkS")
		)
		(fp_line
			(start -0.7874 0.4064)
			(end -0.7874 -0.4064)
			(stroke
				(width 0.1524)
				(type default)
			)
			(layer "F.SilkS")
		)
		(fp_line
			(start 0.7874 -0.4064)
			(end 0.7874 0.4064)
			(stroke
				(width 0.1524)
				(type default)
			)
			(layer "F.SilkS")
		)
		(fp_line
			(start 0.7874 0.4064)
			(end -0.7874 0.4064)
			(stroke
				(width 0.1524)
				(type default)
			)
			(layer "F.SilkS")
		)
		(fp_line
			(start -0.67945 -0.305054)
			(end -0.12065 -0.305054)
			(stroke
				(width 0.1)
				(type default)
			)
			(layer "F.Fab")
		)
		(fp_line
			(start -0.67945 0.3048)
			(end -0.67945 -0.305054)
			(stroke
				(width 0.1)
				(type default)
			)
			(layer "F.Fab")
		)
		(fp_line
			(start -0.12065 -0.305054)
			(end -0.12065 -0.2794)
			(stroke
				(width 0.1)
				(type default)
			)
			(layer "F.Fab")
		)
		(fp_line
			(start -0.12065 -0.2794)
			(end 0.12065 -0.2794)
			(stroke
				(width 0.1)
				(type default)
			)
			(layer "F.Fab")
		)
		(fp_line
			(start -0.12065 0.2794)
			(end -0.12065 0.3048)
			(stroke
				(width 0.1)
				(type default)
			)
			(layer "F.Fab")
		)
		(fp_line
			(start -0.12065 0.3048)
			(end -0.67945 0.3048)
			(stroke
				(width 0.1)
				(type default)
			)
			(layer "F.Fab")
		)
		(fp_line
			(start 0.120396 0.2794)
			(end -0.12065 0.2794)
			(stroke
				(width 0.1)
				(type default)
			)
			(layer "F.Fab")
		)
		(fp_line
			(start 0.120396 0.3048)
			(end 0.120396 0.2794)
			(stroke
				(width 0.1)
				(type default)
			)
			(layer "F.Fab")
		)
		(fp_line
			(start 0.12065 -0.3048)
			(end 0.67945 -0.3048)
			(stroke
				(width 0.1)
				(type default)
			)
			(layer "F.Fab")
		)
		(fp_line
			(start 0.12065 -0.2794)
			(end 0.12065 -0.3048)
			(stroke
				(width 0.1)
				(type default)
			)
			(layer "F.Fab")
		)
		(fp_line
			(start 0.67945 -0.3048)
			(end 0.67945 0.3048)
			(stroke
				(width 0.1)
				(type default)
			)
			(layer "F.Fab")
		)
		(fp_line
			(start 0.67945 0.3048)
			(end 0.120396 0.3048)
			(stroke
				(width 0.1)
				(type default)
			)
			(layer "F.Fab")
		)
		(pad "1" smd circle
			(at -0.40005 0)
			(size 0 0)
			(layers "F.Cu" "F.Mask" "F.Paste")
			(net "P3V3_AUX")
		)
		(pad "2" smd circle
			(at 0.40005 0)
			(size 0 0)
			(layers "F.Cu" "F.Mask" "F.Paste")
			(net "RST_PEX_SSD8_PERST_R_N")
		)
	)
	(footprint ""
		(layer "F.Cu")
		(at 204.752194 -114.892836 180)
		(property "Reference" "PC792"
			(at 0 0 180)
			(layer "F.SilkS")
			(hide yes)
			(effects
				(font
					(size 1.27 1.27)
				)
			)
		)
		(property "Value" ""
			(at 0 0 180)
			(layer "F.Fab")
			(effects
				(font
					(size 1.27 1.27)
				)
			)
		)
		(duplicate_pad_numbers_are_jumpers no)
		(fp_line
			(start 0.7874 0.4064)
			(end -0.7874 0.4064)
			(stroke
				(width 0.1524)
				(type default)
			)
			(layer "F.SilkS")
		)
		(fp_line
			(start 0.7874 -0.4064)
			(end 0.7874 0.4064)
			(stroke
				(width 0.1524)
				(type default)
			)
			(layer "F.SilkS")
		)
		(fp_line
			(start -0.7874 0.4064)
			(end -0.7874 -0.4064)
			(stroke
				(width 0.1524)
				(type default)
			)
			(layer "F.SilkS")
		)
		(fp_line
			(start -0.7874 -0.4064)
			(end 0.7874 -0.4064)
			(stroke
				(width 0.1524)
				(type default)
			)
			(layer "F.SilkS")
		)
		(fp_line
			(start 0.67945 0.3048)
			(end 0.120396 0.3048)
			(stroke
				(width 0.1)
				(type default)
			)
			(layer "F.Fab")
		)
		(fp_line
			(start 0.67945 -0.3048)
			(end 0.67945 0.3048)
			(stroke
				(width 0.1)
				(type default)
			)
			(layer "F.Fab")
		)
		(fp_line
			(start 0.12065 -0.2794)
			(end 0.12065 -0.3048)
			(stroke
				(width 0.1)
				(type default)
			)
			(layer "F.Fab")
		)
		(fp_line
			(start 0.12065 -0.3048)
			(end 0.67945 -0.3048)
			(stroke
				(width 0.1)
				(type default)
			)
			(layer "F.Fab")
		)
		(fp_line
			(start 0.120396 0.3048)
			(end 0.120396 0.2794)
			(stroke
				(width 0.1)
				(type default)
			)
			(layer "F.Fab")
		)
		(fp_line
			(start 0.120396 0.2794)
			(end -0.12065 0.2794)
			(stroke
				(width 0.1)
				(type default)
			)
			(layer "F.Fab")
		)
		(fp_line
			(start -0.12065 0.3048)
			(end -0.67945 0.3048)
			(stroke
				(width 0.1)
				(type default)
			)
			(layer "F.Fab")
		)
		(fp_line
			(start -0.12065 0.2794)
			(end -0.12065 0.3048)
			(stroke
				(width 0.1)
				(type default)
			)
			(layer "F.Fab")
		)
		(fp_line
			(start -0.12065 -0.2794)
			(end 0.12065 -0.2794)
			(stroke
				(width 0.1)
				(type default)
			)
			(layer "F.Fab")
		)
		(fp_line
			(start -0.12065 -0.305054)
			(end -0.12065 -0.2794)
			(stroke
				(width 0.1)
				(type default)
			)
			(layer "F.Fab")
		)
		(fp_line
			(start -0.67945 0.3048)
			(end -0.67945 -0.305054)
			(stroke
				(width 0.1)
				(type default)
			)
			(layer "F.Fab")
		)
		(fp_line
			(start -0.67945 -0.305054)
			(end -0.12065 -0.305054)
			(stroke
				(width 0.1)
				(type default)
			)
			(layer "F.Fab")
		)
		(pad "1" smd circle
			(at -0.40005 0 180)
			(size 0 0)
			(layers "F.Cu" "F.Mask" "F.Paste")
			(net "P3V3_NIC3_CO_GATE")
		)
		(pad "2" smd circle
			(at 0.40005 0 180)
			(size 0 0)
			(layers "F.Cu" "F.Mask" "F.Paste")
			(net "GND")
		)
	)
	(footprint ""
		(layer "F.Cu")
		(at 347.726 -205.232 90)
		(property "Reference" "R4149"
			(at 0 0 90)
			(layer "F.SilkS")
			(hide yes)
			(effects
				(font
					(size 1.27 1.27)
				)
			)
		)
		(property "Value" ""
			(at 0 0 90)
			(layer "F.Fab")
			(effects
				(font
					(size 1.27 1.27)
				)
			)
		)
		(duplicate_pad_numbers_are_jumpers no)
		(fp_line
			(start 0.7874 -0.4064)
			(end 0.7874 0.4064)
			(stroke
				(width 0.1524)
				(type default)
			)
			(layer "F.SilkS")
		)
		(fp_line
			(start -0.7874 -0.4064)
			(end 0.7874 -0.4064)
			(stroke
				(width 0.1524)
				(type default)
			)
			(layer "F.SilkS")
		)
		(fp_line
			(start 0.7874 0.4064)
			(end -0.7874 0.4064)
			(stroke
				(width 0.1524)
				(type default)
			)
			(layer "F.SilkS")
		)
		(fp_line
			(start -0.7874 0.4064)
			(end -0.7874 -0.4064)
			(stroke
				(width 0.1524)
				(type default)
			)
			(layer "F.SilkS")
		)
		(fp_line
			(start -0.12065 -0.305054)
			(end -0.12065 -0.2794)
			(stroke
				(width 0.1)
				(type default)
			)
			(layer "F.Fab")
		)
		(fp_line
			(start -0.67945 -0.305054)
			(end -0.12065 -0.305054)
			(stroke
				(width 0.1)
				(type default)
			)
			(layer "F.Fab")
		)
		(fp_line
			(start 0.67945 -0.3048)
			(end 0.67945 0.3048)
			(stroke
				(width 0.1)
				(type default)
			)
			(layer "F.Fab")
		)
		(fp_line
			(start 0.12065 -0.3048)
			(end 0.67945 -0.3048)
			(stroke
				(width 0.1)
				(type default)
			)
			(layer "F.Fab")
		)
		(fp_line
			(start 0.12065 -0.2794)
			(end 0.12065 -0.3048)
			(stroke
				(width 0.1)
				(type default)
			)
			(layer "F.Fab")
		)
		(fp_line
			(start -0.12065 -0.2794)
			(end 0.12065 -0.2794)
			(stroke
				(width 0.1)
				(type default)
			)
			(layer "F.Fab")
		)
		(fp_line
			(start 0.120396 0.2794)
			(end -0.12065 0.2794)
			(stroke
				(width 0.1)
				(type default)
			)
			(layer "F.Fab")
		)
		(fp_line
			(start -0.12065 0.2794)
			(end -0.12065 0.3048)
			(stroke
				(width 0.1)
				(type default)
			)
			(layer "F.Fab")
		)
		(fp_line
			(start 0.67945 0.3048)
			(end 0.120396 0.3048)
			(stroke
				(width 0.1)
				(type default)
			)
			(layer "F.Fab")
		)
		(fp_line
			(start 0.120396 0.3048)
			(end 0.120396 0.2794)
			(stroke
				(width 0.1)
				(type default)
			)
			(layer "F.Fab")
		)
		(fp_line
			(start -0.12065 0.3048)
			(end -0.67945 0.3048)
			(stroke
				(width 0.1)
				(type default)
			)
			(layer "F.Fab")
		)
		(fp_line
			(start -0.67945 0.3048)
			(end -0.67945 -0.305054)
			(stroke
				(width 0.1)
				(type default)
			)
			(layer "F.Fab")
		)
		(pad "1" smd circle
			(at -0.40005 0 90)
			(size 0 0)
			(layers "F.Cu" "F.Mask" "F.Paste")
			(net "PRSNT_SSD2_FPGA_R_N")
		)
		(pad "2" smd circle
			(at 0.40005 0 90)
			(size 0 0)
			(layers "F.Cu" "F.Mask" "F.Paste")
			(net "PRSNT_SSD2_FPGA_N")
		)
	)
	(footprint ""
		(layer "F.Cu")
		(at 57.341262 -390.07161 -90)
		(property "Reference" "R1828"
			(at 0 0 270)
			(layer "F.SilkS")
			(hide yes)
			(effects
				(font
					(size 1.27 1.27)
				)
			)
		)
		(property "Value" ""
			(at 0 0 270)
			(layer "F.Fab")
			(effects
				(font
					(size 1.27 1.27)
				)
			)
		)
		(duplicate_pad_numbers_are_jumpers no)
		(fp_line
			(start -0.7874 0.4064)
			(end -0.7874 -0.4064)
			(stroke
				(width 0.1524)
				(type default)
			)
			(layer "F.SilkS")
		)
		(fp_line
			(start 0.7874 0.4064)
			(end -0.7874 0.4064)
			(stroke
				(width 0.1524)
				(type default)
			)
			(layer "F.SilkS")
		)
		(fp_line
			(start -0.7874 -0.4064)
			(end 0.7874 -0.4064)
			(stroke
				(width 0.1524)
				(type default)
			)
			(layer "F.SilkS")
		)
		(fp_line
			(start 0.7874 -0.4064)
			(end 0.7874 0.4064)
			(stroke
				(width 0.1524)
				(type default)
			)
			(layer "F.SilkS")
		)
		(fp_line
			(start -0.67945 0.3048)
			(end -0.67945 -0.305054)
			(stroke
				(width 0.1)
				(type default)
			)
			(layer "F.Fab")
		)
		(fp_line
			(start -0.12065 0.3048)
			(end -0.67945 0.3048)
			(stroke
				(width 0.1)
				(type default)
			)
			(layer "F.Fab")
		)
		(fp_line
			(start 0.120396 0.3048)
			(end 0.120396 0.2794)
			(stroke
				(width 0.1)
				(type default)
			)
			(layer "F.Fab")
		)
		(fp_line
			(start 0.67945 0.3048)
			(end 0.120396 0.3048)
			(stroke
				(width 0.1)
				(type default)
			)
			(layer "F.Fab")
		)
		(fp_line
			(start -0.12065 0.2794)
			(end -0.12065 0.3048)
			(stroke
				(width 0.1)
				(type default)
			)
			(layer "F.Fab")
		)
		(fp_line
			(start 0.120396 0.2794)
			(end -0.12065 0.2794)
			(stroke
				(width 0.1)
				(type default)
			)
			(layer "F.Fab")
		)
		(fp_line
			(start -0.12065 -0.2794)
			(end 0.12065 -0.2794)
			(stroke
				(width 0.1)
				(type default)
			)
			(layer "F.Fab")
		)
		(fp_line
			(start 0.12065 -0.2794)
			(end 0.12065 -0.3048)
			(stroke
				(width 0.1)
				(type default)
			)
			(layer "F.Fab")
		)
		(fp_line
			(start 0.12065 -0.3048)
			(end 0.67945 -0.3048)
			(stroke
				(width 0.1)
				(type default)
			)
			(layer "F.Fab")
		)
		(fp_line
			(start 0.67945 -0.3048)
			(end 0.67945 0.3048)
			(stroke
				(width 0.1)
				(type default)
			)
			(layer "F.Fab")
		)
		(fp_line
			(start -0.67945 -0.305054)
			(end -0.12065 -0.305054)
			(stroke
				(width 0.1)
				(type default)
			)
			(layer "F.Fab")
		)
		(fp_line
			(start -0.12065 -0.305054)
			(end -0.12065 -0.2794)
			(stroke
				(width 0.1)
				(type default)
			)
			(layer "F.Fab")
		)
		(pad "1" smd circle
			(at -0.40005 0 270)
			(size 0 0)
			(layers "F.Cu" "F.Mask" "F.Paste")
			(net "GPU_PEX_STRAP0_R")
		)
		(pad "2" smd circle
			(at 0.40005 0 270)
			(size 0 0)
			(layers "F.Cu" "F.Mask" "F.Paste")
			(net "GPU_PEX_STRAP0")
		)
	)
	(footprint ""
		(layer "F.Cu")
		(at 286.695134 -35.48253)
		(property "Reference" "U393"
			(at -2.569464 1.09093 90)
			(unlocked yes)
			(layer "F.SilkS")
			(effects
				(font
					(size 0.7874 0.5842)
					(thickness 0.1524)
				)
				(justify left)
			)
		)
		(property "Value" ""
			(at 0 0 0)
			(layer "F.Fab")
			(effects
				(font
					(size 1.27 1.27)
				)
			)
		)
		(duplicate_pad_numbers_are_jumpers no)
		(fp_line
			(start -1.3462 -1.1938)
			(end -1.3462 1.1684)
			(stroke
				(width 0.1524)
				(type default)
			)
			(layer "F.SilkS")
		)
		(fp_line
			(start -1.3462 1.1938)
			(end 1.3462 1.1938)
			(stroke
				(width 0.1524)
				(type default)
			)
			(layer "F.SilkS")
		)
		(fp_line
			(start 1.3462 -1.1938)
			(end -1.3462 -1.1938)
			(stroke
				(width 0.1524)
				(type default)
			)
			(layer "F.SilkS")
		)
		(fp_line
			(start 1.3462 1.1938)
			(end 1.3462 -1.1938)
			(stroke
				(width 0.1524)
				(type default)
			)
			(layer "F.SilkS")
		)
		(fp_poly
			(pts
				(xy -1.447038 -0.760476) (xy -2.052066 -0.457962) (xy -2.052066 -1.06299)
			)
			(stroke
				(width 0)
				(type default)
			)
			(fill yes)
			(layer "F.SilkS")
		)
		(fp_line
			(start -0.674878 -1.124966)
			(end -0.674878 1.124966)
			(stroke
				(width 0.1)
				(type default)
			)
			(layer "F.Fab")
		)
		(fp_line
			(start -0.674878 1.124966)
			(end 0.674878 1.124966)
			(stroke
				(width 0.1)
				(type default)
			)
			(layer "F.Fab")
		)
		(fp_line
			(start 0.674878 -1.124966)
			(end -0.674878 -1.124966)
			(stroke
				(width 0.1)
				(type default)
			)
			(layer "F.Fab")
		)
		(fp_line
			(start 0.674878 1.124966)
			(end 0.674878 -1.124966)
			(stroke
				(width 0.1)
				(type default)
			)
			(layer "F.Fab")
		)
		(fp_poly
			(pts
				(xy -1.447038 -0.760476) (xy -2.052066 -0.457962) (xy -2.052066 -1.06299)
			)
			(stroke
				(width 0)
				(type default)
			)
			(fill yes)
			(layer "F.Fab")
		)
		(pad "1" smd rect
			(at -0.899922 -0.750062)
			(size 0.6096 0.6096)
			(layers "F.Cu" "F.Mask" "F.Paste")
			(net "PWRGD_P3V3_SSD10_R")
		)
		(pad "2" smd rect
			(at -0.899922 0 90)
			(size 0.4064 0.6096)
			(layers "F.Cu" "F.Mask" "F.Paste")
			(net "RST_SMB_SSD10_N")
		)
		(pad "3" smd rect
			(at -0.899922 0.750062)
			(size 0.6096 0.6096)
			(layers "F.Cu" "F.Mask" "F.Paste")
			(net "GND")
		)
		(pad "4" smd rect
			(at 0.899922 0.750062)
			(size 0.6096 0.6096)
			(layers "F.Cu" "F.Mask" "F.Paste")
			(net "RST_SMB_SSD10_ISO_N")
		)
		(pad "5" smd rect
			(at 0.899922 -0.750062)
			(size 0.6096 0.6096)
			(layers "F.Cu" "F.Mask" "F.Paste")
			(net "P3V3_AUX")
		)
	)
)
